(kicad_pcb
	(version 20240108)
	(generator "pcbnew")
	(generator_version "8.0")
	(general
		(thickness 1.62)
		(legacy_teardrops no)
	)
	(paper "A4")
	(title_block
		(title "Jetson Orin Baseboard")
		(date "2025-03-12")
		(rev "1.3.4")
		(company "Antmicro Ltd")
		(comment 1 "www.antmicro.com")
		(comment 9 "footprints 48-52 of 677")
	)
	(layers
		(0 "F.Cu" signal)
		(1 "In1.Cu" signal)
		(2 "In2.Cu" signal)
		(3 "In3.Cu" signal)
		(4 "In4.Cu" jumper)
		(5 "In5.Cu" signal)
		(6 "In6.Cu" signal)
		(31 "B.Cu" signal)
		(32 "B.Adhes" user "B.Adhesive")
		(33 "F.Adhes" user "F.Adhesive")
		(34 "B.Paste" user)
		(35 "F.Paste" user)
		(36 "B.SilkS" user "B.Silkscreen")
		(37 "F.SilkS" user "F.Silkscreen")
		(38 "B.Mask" user)
		(39 "F.Mask" user)
		(40 "Dwgs.User" user "User.Drawings")
		(41 "Cmts.User" user "User.Comments")
		(42 "Eco1.User" user "User.Eco1")
		(43 "Eco2.User" user "User.Eco2")
		(44 "Edge.Cuts" user)
		(45 "Margin" user)
		(46 "B.CrtYd" user "B.Courtyard")
		(47 "F.CrtYd" user "F.Courtyard")
		(48 "B.Fab" user)
		(49 "F.Fab" user)
	)
	(footprint "antmicro-footprints:C_0402_1005Metric"
		(layer "F.Cu")
		(at 127.05 94.2 180)
		(descr "Capacitor SMD 0402")
		(tags "capacitor SMD 0402")
		(property "Reference" "C9"
			(at 0.7 0.4 180)
			(layer "F.SilkS")
			(effects
				(font
					(size 0.7 0.7)
					(thickness 0.15)
				)
				(justify left bottom)
			)
		)
		(property "Value" "C_220n_0402"
			(at 0 1.4 180)
			(layer "F.Fab")
			(effects
				(font
					(size 0.7 0.7)
					(thickness 0.15)
				)
				(justify left bottom)
			)
		)
		(property "Footprint" "antmicro-footprints:C_0402_1005Metric"
			(at 0 0 180)
			(layer "F.Fab")
			(hide yes)
			(effects
				(font
					(size 1.27 1.27)
					(thickness 0.15)
				)
			)
		)
		(property "Datasheet" "https://www.yageo.com/en/Chart/Download/pdf/CC0402KRX5R6BB224"
			(at 0 0 180)
			(layer "F.Fab")
			(hide yes)
			(effects
				(font
					(size 1.27 1.27)
					(thickness 0.15)
				)
			)
		)
		(property "Author" "Antmicro"
			(at 254.1 188.4 0)
			(layer "F.Fab")
			(hide yes)
			(effects
				(font
					(size 1 1)
					(thickness 0.15)
				)
			)
		)
		(property "Dielectric" ""
			(at 254.1 188.4 0)
			(layer "F.Fab")
			(hide yes)
			(effects
				(font
					(size 1 1)
					(thickness 0.15)
				)
			)
		)
		(property "License" "Apache-2.0"
			(at 254.1 188.4 0)
			(layer "F.Fab")
			(hide yes)
			(effects
				(font
					(size 1 1)
					(thickness 0.15)
				)
			)
		)
		(property "MPN" "CC0402KRX5R6BB224"
			(at 254.1 188.4 0)
			(layer "F.Fab")
			(hide yes)
			(effects
				(font
					(size 1 1)
					(thickness 0.15)
				)
			)
		)
		(property "Manufacturer" "YAGEO"
			(at 254.1 188.4 0)
			(layer "F.Fab")
			(hide yes)
			(effects
				(font
					(size 1 1)
					(thickness 0.15)
				)
			)
		)
		(property "Val" "220n"
			(at 254.1 188.4 0)
			(layer "F.Fab")
			(hide yes)
			(effects
				(font
					(size 1 1)
					(thickness 0.15)
				)
			)
		)
		(property "Voltage" ""
			(at 254.1 188.4 0)
			(layer "F.Fab")
			(hide yes)
			(effects
				(font
					(size 1 1)
					(thickness 0.15)
				)
			)
		)
		(sheetname "M.2")
		(sheetfile "m-2.kicad_sch")
		(attr smd)
		(fp_rect
			(start -0.925 -0.47)
			(end 0.925 0.47)
			(stroke
				(width 0.05)
				(type default)
			)
			(fill none)
			(layer "F.CrtYd")
		)
		(fp_line
			(start 0.504 0.248)
			(end -0.494 0.248)
			(stroke
				(width 0.15)
				(type solid)
			)
			(layer "F.Fab")
		)
		(fp_line
			(start 0.504 -0.25)
			(end 0.504 0.248)
			(stroke
				(width 0.15)
				(type solid)
			)
			(layer "F.Fab")
		)
		(fp_line
			(start -0.494 0.248)
			(end -0.494 -0.25)
			(stroke
				(width 0.15)
				(type solid)
			)
			(layer "F.Fab")
		)
		(fp_line
			(start -0.494 -0.25)
			(end 0.504 -0.25)
			(stroke
				(width 0.15)
				(type solid)
			)
			(layer "F.Fab")
		)
		(fp_text user "License: Apache-2.0"
			(at -0.932 5.17 180)
			(layer "F.Fab")
			(hide yes)
			(effects
				(font
					(size 0.7 0.7)
					(thickness 0.15)
				)
				(justify left bottom)
			)
		)
		(fp_text user "Author: Antmicro"
			(at -0.932 4.17 180)
			(layer "F.Fab")
			(hide yes)
			(effects
				(font
					(size 0.7 0.7)
					(thickness 0.15)
				)
				(justify left bottom)
			)
		)
		(fp_text user "${REFERENCE}"
			(at -0.932 3.168 180)
			(layer "F.Fab")
			(hide yes)
			(effects
				(font
					(size 0.7 0.7)
					(thickness 0.15)
				)
				(justify left bottom)
			)
		)
		(pad "1" smd roundrect
			(at -0.48 0 180)
			(size 0.59 0.64)
			(layers "F.Cu" "F.Paste" "F.Mask")
			(roundrect_rratio 0.25)
			(net 451 "PCIE1_TX0_P")
			(pintype "passive")
		)
		(pad "2" smd roundrect
			(at 0.48 0 180)
			(size 0.59 0.64)
			(layers "F.Cu" "F.Paste" "F.Mask")
			(roundrect_rratio 0.25)
			(net 96 "/M.2/C_PCIE1_TX0_P")
			(pintype "passive")
		)
	)
	(footprint "antmicro-footprints:USON-10_2.5x1mm_P0.5mm"
		(layer "F.Cu")
		(at 93.625 119.9 90)
		(descr "USON-10 2.5x1mm_ Pitch 0.5mm")
		(tags "USON-10 2.5x1mm Pitch 0.5mm")
		(property "Reference" "U45"
			(at -0.1 5.425 -90)
			(layer "F.SilkS")
			(effects
				(font
					(size 0.7 0.7)
					(thickness 0.15)
				)
				(justify left bottom)
			)
		)
		(property "Value" "TPD4E05U06QDQARQ1"
			(at 0.018 2.499 90)
			(layer "F.Fab")
			(effects
				(font
					(size 0.7 0.7)
					(thickness 0.15)
				)
				(justify left bottom)
			)
		)
		(property "Footprint" "antmicro-footprints:USON-10_2.5x1mm_P0.5mm"
			(at 0 0 90)
			(layer "F.Fab")
			(hide yes)
			(effects
				(font
					(size 1.27 1.27)
					(thickness 0.15)
				)
			)
		)
		(property "Datasheet" "https://www.ti.com/lit/ds/symlink/tpd4e05u06-q1.pdf?HQS=dis-mous-null-mousermode-dsf-pf-null-wwe&ts=1663591265741&ref_url=https%253A%252F%252Fwww.mouser.com%252F"
			(at 0 0 90)
			(layer "F.Fab")
			(hide yes)
			(effects
				(font
					(size 1.27 1.27)
					(thickness 0.15)
				)
			)
		)
		(property "Author" "Antmicro"
			(at 213.525 26.275 0)
			(layer "F.Fab")
			(hide yes)
			(effects
				(font
					(size 1 1)
					(thickness 0.15)
				)
			)
		)
		(property "License" "Apache-2.0"
			(at 213.525 26.275 0)
			(layer "F.Fab")
			(hide yes)
			(effects
				(font
					(size 1 1)
					(thickness 0.15)
				)
			)
		)
		(property "MPN" "TPD4E05U06QDQARQ1"
			(at 213.525 26.275 0)
			(layer "F.Fab")
			(hide yes)
			(effects
				(font
					(size 1 1)
					(thickness 0.15)
				)
			)
		)
		(property "Manufacturer" "Texas Instruments"
			(at 213.525 26.275 0)
			(layer "F.Fab")
			(hide yes)
			(effects
				(font
					(size 1 1)
					(thickness 0.15)
				)
			)
		)
		(sheetname "HDMI")
		(sheetfile "hdmi.kicad_sch")
		(attr smd)
		(fp_line
			(start 0.498 -1.401)
			(end -0.5 -1.401)
			(stroke
				(width 0.15)
				(type solid)
			)
			(layer "F.SilkS")
		)
		(fp_line
			(start 0.498 1.398)
			(end -0.5 1.398)
			(stroke
				(width 0.15)
				(type solid)
			)
			(layer "F.SilkS")
		)
		(fp_circle
			(center -0.68 -1.27)
			(end -0.63 -1.27)
			(stroke
				(width 0.15)
				(type solid)
			)
			(fill solid)
			(layer "F.SilkS")
		)
		(fp_rect
			(start -0.8 -1.5)
			(end 0.8 1.499)
			(stroke
				(width 0.05)
				(type solid)
			)
			(fill none)
			(layer "F.CrtYd")
		)
		(fp_line
			(start 0.498 -1.25)
			(end -0.25 -1.25)
			(stroke
				(width 0.15)
				(type solid)
			)
			(layer "F.Fab")
		)
		(fp_line
			(start 0.498 -1.25)
			(end 0.498 1.249)
			(stroke
				(width 0.15)
				(type solid)
			)
			(layer "F.Fab")
		)
		(fp_line
			(start -0.25 -1.25)
			(end -0.5 -1)
			(stroke
				(width 0.15)
				(type solid)
			)
			(layer "F.Fab")
		)
		(fp_line
			(start -0.5 -1)
			(end -0.5 1.249)
			(stroke
				(width 0.15)
				(type solid)
			)
			(layer "F.Fab")
		)
		(fp_line
			(start -0.5 1.249)
			(end 0.498 1.249)
			(stroke
				(width 0.15)
				(type solid)
			)
			(layer "F.Fab")
		)
		(fp_text user "License: Apache-2.0"
			(at -0.802 6.9 90)
			(layer "F.Fab")
			(hide yes)
			(effects
				(font
					(size 0.7 0.7)
					(thickness 0.15)
				)
				(justify left bottom)
			)
		)
		(fp_text user "Author: Antmicro"
			(at -0.802 5.7 90)
			(layer "F.Fab")
			(hide yes)
			(effects
				(font
					(size 0.7 0.7)
					(thickness 0.15)
				)
				(justify left bottom)
			)
		)
		(fp_text user "${REFERENCE}"
			(at -0.802 4.498 90)
			(layer "F.Fab")
			(hide yes)
			(effects
				(font
					(size 0.7 0.7)
					(thickness 0.15)
				)
				(justify left bottom)
			)
		)
		(pad "1" smd roundrect
			(at -0.387 -1)
			(size 0.25 0.55)
			(layers "F.Cu" "F.Paste" "F.Mask")
			(roundrect_rratio 0.25)
			(net 521 "/HDMI/HDMI_CLK_CONN_N")
			(pintype "passive")
		)
		(pad "2" smd roundrect
			(at -0.387 -0.5)
			(size 0.25 0.55)
			(layers "F.Cu" "F.Paste" "F.Mask")
			(roundrect_rratio 0.25)
			(net 522 "/HDMI/HDMI_CLK_CONN_P")
			(pintype "passive")
		)
		(pad "3" smd roundrect
			(at -0.387 0)
			(size 0.4 0.55)
			(layers "F.Cu" "F.Paste" "F.Mask")
			(roundrect_rratio 0.25)
			(net 1 "GND")
			(pintype "power_in")
		)
		(pad "4" smd roundrect
			(at -0.387 0.498)
			(size 0.25 0.55)
			(layers "F.Cu" "F.Paste" "F.Mask")
			(roundrect_rratio 0.25)
			(net 523 "/HDMI/HDMI_D0_CONN_N")
			(pintype "passive")
		)
		(pad "5" smd roundrect
			(at -0.387 0.998)
			(size 0.25 0.55)
			(layers "F.Cu" "F.Paste" "F.Mask")
			(roundrect_rratio 0.25)
			(net 524 "/HDMI/HDMI_D0_CONN_P")
			(pintype "passive")
		)
		(pad "6" smd roundrect
			(at 0.385 0.998)
			(size 0.25 0.55)
			(layers "F.Cu" "F.Paste" "F.Mask")
			(roundrect_rratio 0.25)
			(net 524 "/HDMI/HDMI_D0_CONN_P")
			(pintype "passive")
		)
		(pad "7" smd roundrect
			(at 0.385 0.498)
			(size 0.25 0.55)
			(layers "F.Cu" "F.Paste" "F.Mask")
			(roundrect_rratio 0.25)
			(net 523 "/HDMI/HDMI_D0_CONN_N")
			(pintype "passive")
		)
		(pad "8" smd roundrect
			(at 0.385 0)
			(size 0.4 0.55)
			(layers "F.Cu" "F.Paste" "F.Mask")
			(roundrect_rratio 0.25)
			(net 1 "GND")
			(pintype "passive")
		)
		(pad "9" smd roundrect
			(at 0.385 -0.5)
			(size 0.25 0.55)
			(layers "F.Cu" "F.Paste" "F.Mask")
			(roundrect_rratio 0.25)
			(net 522 "/HDMI/HDMI_CLK_CONN_P")
			(pintype "passive")
		)
		(pad "10" smd roundrect
			(at 0.385 -1)
			(size 0.25 0.55)
			(layers "F.Cu" "F.Paste" "F.Mask")
			(roundrect_rratio 0.25)
			(net 521 "/HDMI/HDMI_CLK_CONN_N")
			(pintype "passive")
		)
	)
	(footprint "antmicro-footprints:TP_SMD_0.75mm"
		(layer "F.Cu")
		(at 65.48 122.485)
		(property "Reference" "TP28"
			(at 0.45 -0.42 90)
			(layer "F.SilkS")
			(effects
				(font
					(size 0.7 0.7)
					(thickness 0.15)
				)
				(justify left bottom)
			)
		)
		(property "Value" "TP_0.75mm_SMD"
			(at 0 1.2 0)
			(layer "F.Fab")
			(effects
				(font
					(size 0.7 0.7)
					(thickness 0.15)
				)
				(justify left bottom)
			)
		)
		(property "Footprint" "antmicro-footprints:TP_SMD_0.75mm"
			(at 0 0 0)
			(layer "F.Fab")
			(hide yes)
			(effects
				(font
					(size 1.27 1.27)
					(thickness 0.15)
				)
			)
		)
		(property "Author" "Antmicro"
			(at 0 0 0)
			(layer "F.Fab")
			(hide yes)
			(effects
				(font
					(size 1 1)
					(thickness 0.15)
				)
			)
		)
		(property "License" "Apache-2.0"
			(at 0 0 0)
			(layer "F.Fab")
			(hide yes)
			(effects
				(font
					(size 1 1)
					(thickness 0.15)
				)
			)
		)
		(property "MPN" ""
			(at 0 0 0)
			(layer "F.Fab")
			(hide yes)
			(effects
				(font
					(size 1 1)
					(thickness 0.15)
				)
			)
		)
		(property "Manufacturer" ""
			(at 0 0 0)
			(layer "F.Fab")
			(hide yes)
			(effects
				(font
					(size 1 1)
					(thickness 0.15)
				)
			)
		)
		(sheetname "USB Debug, DP")
		(sheetfile "usb.kicad_sch")
		(attr exclude_from_pos_files exclude_from_bom)
		(fp_circle
			(center 0 0)
			(end 0.475 0)
			(stroke
				(width 0.05)
				(type default)
			)
			(fill none)
			(layer "F.CrtYd")
		)
		(fp_text user "License: Apache-2.0"
			(at -0.4 5.101 0)
			(layer "F.Fab")
			(hide yes)
			(effects
				(font
					(size 0.7 0.7)
					(thickness 0.15)
				)
				(justify left bottom)
			)
		)
		(fp_text user "${REFERENCE}"
			(at -0.4 2.7 0)
			(layer "F.Fab")
			(hide yes)
			(effects
				(font
					(size 0.7 0.7)
					(thickness 0.15)
				)
				(justify left bottom)
			)
		)
		(fp_text user "Author: Antmicro"
			(at -0.4 3.901 0)
			(layer "F.Fab")
			(hide yes)
			(effects
				(font
					(size 0.7 0.7)
					(thickness 0.15)
				)
				(justify left bottom)
			)
		)
		(pad "1" smd circle
			(at 0 0)
			(size 0.75 0.75)
			(layers "F.Cu" "F.Mask")
			(net 692 "Net-(U10-CAD_SNK{slash}RSVD1)")
			(pinfunction "1")
			(pintype "passive")
		)
	)
	(footprint "antmicro-footprints:C_0402_1005Metric"
		(layer "F.Cu")
		(at 78.62 110.34 -90)
		(descr "Capacitor SMD 0402")
		(tags "capacitor SMD 0402")
		(property "Reference" "C37"
			(at 1.11 -1.33 -90)
			(layer "F.SilkS")
			(effects
				(font
					(size 0.7 0.7)
					(thickness 0.15)
				)
				(justify left bottom)
			)
		)
		(property "Value" "C_100n_0402"
			(at 0 1.4 -90)
			(layer "F.Fab")
			(effects
				(font
					(size 0.7 0.7)
					(thickness 0.15)
				)
				(justify left bottom)
			)
		)
		(property "Footprint" "antmicro-footprints:C_0402_1005Metric"
			(at 0 0 -90)
			(layer "F.Fab")
			(hide yes)
			(effects
				(font
					(size 1.27 1.27)
					(thickness 0.15)
				)
			)
		)
		(property "Datasheet" "https://www.murata.com/products/productdetail?partno=GRM155R61H104KE14%23"
			(at 0 0 -90)
			(layer "F.Fab")
			(hide yes)
			(effects
				(font
					(size 1.27 1.27)
					(thickness 0.15)
				)
			)
		)
		(property "Author" "Antmicro"
			(at -31.72 188.96 0)
			(layer "F.Fab")
			(hide yes)
			(effects
				(font
					(size 1 1)
					(thickness 0.15)
				)
			)
		)
		(property "Dielectric" "X5R"
			(at -31.72 188.96 0)
			(layer "F.Fab")
			(hide yes)
			(effects
				(font
					(size 1 1)
					(thickness 0.15)
				)
			)
		)
		(property "License" "Apache-2.0"
			(at -31.72 188.96 0)
			(layer "F.Fab")
			(hide yes)
			(effects
				(font
					(size 1 1)
					(thickness 0.15)
				)
			)
		)
		(property "MPN" "GRM155R61H104KE14D"
			(at -31.72 188.96 0)
			(layer "F.Fab")
			(hide yes)
			(effects
				(font
					(size 1 1)
					(thickness 0.15)
				)
			)
		)
		(property "Manufacturer" "Murata"
			(at -31.72 188.96 0)
			(layer "F.Fab")
			(hide yes)
			(effects
				(font
					(size 1 1)
					(thickness 0.15)
				)
			)
		)
		(property "Val" "100n"
			(at -31.72 188.96 0)
			(layer "F.Fab")
			(hide yes)
			(effects
				(font
					(size 1 1)
					(thickness 0.15)
				)
			)
		)
		(property "Voltage" "50V"
			(at -31.72 188.96 0)
			(layer "F.Fab")
			(hide yes)
			(effects
				(font
					(size 1 1)
					(thickness 0.15)
				)
			)
		)
		(sheetname "USB Debug, DP")
		(sheetfile "usb.kicad_sch")
		(attr smd)
		(fp_rect
			(start -0.925 -0.47)
			(end 0.925 0.47)
			(stroke
				(width 0.05)
				(type default)
			)
			(fill none)
			(layer "F.CrtYd")
		)
		(fp_line
			(start -0.494 0.248)
			(end -0.494 -0.25)
			(stroke
				(width 0.15)
				(type solid)
			)
			(layer "F.Fab")
		)
		(fp_line
			(start 0.504 0.248)
			(end -0.494 0.248)
			(stroke
				(width 0.15)
				(type solid)
			)
			(layer "F.Fab")
		)
		(fp_line
			(start -0.494 -0.25)
			(end 0.504 -0.25)
			(stroke
				(width 0.15)
				(type solid)
			)
			(layer "F.Fab")
		)
		(fp_line
			(start 0.504 -0.25)
			(end 0.504 0.248)
			(stroke
				(width 0.15)
				(type solid)
			)
			(layer "F.Fab")
		)
		(fp_text user "License: Apache-2.0"
			(at -0.932 5.17 -90)
			(layer "F.Fab")
			(hide yes)
			(effects
				(font
					(size 0.7 0.7)
					(thickness 0.15)
				)
				(justify left bottom)
			)
		)
		(fp_text user "${REFERENCE}"
			(at -0.932 3.168 -90)
			(layer "F.Fab")
			(hide yes)
			(effects
				(font
					(size 0.7 0.7)
					(thickness 0.15)
				)
				(justify left bottom)
			)
		)
		(fp_text user "Author: Antmicro"
			(at -0.932 4.17 -90)
			(layer "F.Fab")
			(hide yes)
			(effects
				(font
					(size 0.7 0.7)
					(thickness 0.15)
				)
				(justify left bottom)
			)
		)
		(pad "1" smd roundrect
			(at -0.48 0 270)
			(size 0.59 0.64)
			(layers "F.Cu" "F.Paste" "F.Mask")
			(roundrect_rratio 0.25)
			(net 87 "+3V3")
			(pintype "passive")
		)
		(pad "2" smd roundrect
			(at 0.48 0 270)
			(size 0.59 0.64)
			(layers "F.Cu" "F.Paste" "F.Mask")
			(roundrect_rratio 0.25)
			(net 1 "GND")
			(pintype "passive")
		)
	)
	(footprint "antmicro-footprints:C_0402_1005Metric"
		(layer "F.Cu")
		(at 74.07 89.44 -90)
		(descr "Capacitor SMD 0402")
		(tags "capacitor SMD 0402")
		(property "Reference" "C121"
			(at -3.63 -0.4 90)
			(layer "F.SilkS")
			(effects
				(font
					(size 0.7 0.7)
					(thickness 0.15)
				)
				(justify right bottom)
			)
		)
		(property "Value" "C_100n_0402"
			(at -1.022927 2.155213 90)
			(layer "F.Fab")
			(effects
				(font
					(size 0.7 0.7)
					(thickness 0.15)
				)
				(justify right bottom)
			)
		)
		(property "Footprint" "antmicro-footprints:C_0402_1005Metric"
			(at 0 0 -90)
			(layer "F.Fab")
			(hide yes)
			(effects
				(font
					(size 1.27 1.27)
					(thickness 0.15)
				)
			)
		)
		(property "Datasheet" "https://www.murata.com/products/productdetail?partno=GRM155R61H104KE14%23"
			(at 0 0 -90)
			(layer "F.Fab")
			(hide yes)
			(effects
				(font
					(size 1.27 1.27)
					(thickness 0.15)
				)
			)
		)
		(property "Author" "Antmicro"
			(at -15.37 163.51 0)
			(layer "F.Fab")
			(hide yes)
			(effects
				(font
					(size 1 1)
					(thickness 0.15)
				)
			)
		)
		(property "Dielectric" "X5R"
			(at -15.37 163.51 0)
			(layer "F.Fab")
			(hide yes)
			(effects
				(font
					(size 1 1)
					(thickness 0.15)
				)
			)
		)
		(property "License" "Apache-2.0"
			(at -15.37 163.51 0)
			(layer "F.Fab")
			(hide yes)
			(effects
				(font
					(size 1 1)
					(thickness 0.15)
				)
			)
		)
		(property "MPN" "GRM155R61H104KE14D"
			(at -15.37 163.51 0)
			(layer "F.Fab")
			(hide yes)
			(effects
				(font
					(size 1 1)
					(thickness 0.15)
				)
			)
		)
		(property "Manufacturer" "Murata"
			(at -15.37 163.51 0)
			(layer "F.Fab")
			(hide yes)
			(effects
				(font
					(size 1 1)
					(thickness 0.15)
				)
			)
		)
		(property "Val" "100n"
			(at -15.37 163.51 0)
			(layer "F.Fab")
			(hide yes)
			(effects
				(font
					(size 1 1)
					(thickness 0.15)
				)
			)
		)
		(property "Voltage" "50V"
			(at -15.37 163.51 0)
			(layer "F.Fab")
			(hide yes)
			(effects
				(font
					(size 1 1)
					(thickness 0.15)
				)
			)
		)
		(sheetname "Supply")
		(sheetfile "supply.kicad_sch")
		(attr smd)
		(fp_rect
			(start -0.925 -0.47)
			(end 0.925 0.47)
			(stroke
				(width 0.05)
				(type default)
			)
			(fill none)
			(layer "F.CrtYd")
		)
		(fp_line
			(start -0.494 0.248)
			(end -0.494 -0.25)
			(stroke
				(width 0.15)
				(type solid)
			)
			(layer "F.Fab")
		)
		(fp_line
			(start 0.504 0.248)
			(end -0.494 0.248)
			(stroke
				(width 0.15)
				(type solid)
			)
			(layer "F.Fab")
		)
		(fp_line
			(start -0.494 -0.25)
			(end 0.504 -0.25)
			(stroke
				(width 0.15)
				(type solid)
			)
			(layer "F.Fab")
		)
		(fp_line
			(start 0.504 -0.25)
			(end 0.504 0.248)
			(stroke
				(width 0.15)
				(type solid)
			)
			(layer "F.Fab")
		)
		(fp_text user "License: Apache-2.0"
			(at -0.939 5.799 90)
			(layer "F.Fab")
			(hide yes)
			(effects
				(font
					(size 0.7 0.7)
					(thickness 0.15)
				)
				(justify right bottom)
			)
		)
		(fp_text user "Author: Antmicro"
			(at -0.939 3.399 90)
			(layer "F.Fab")
			(hide yes)
			(effects
				(font
					(size 0.7 0.7)
					(thickness 0.15)
				)
				(justify right bottom)
			)
		)
		(fp_text user "${REFERENCE}"
			(at -0.939 4.599 90)
			(layer "F.Fab")
			(hide yes)
			(effects
				(font
					(size 0.7 0.7)
					(thickness 0.15)
				)
				(justify right bottom)
			)
		)
		(pad "1" smd roundrect
			(at -0.48 0 270)
			(size 0.59 0.64)
			(layers "F.Cu" "F.Paste" "F.Mask")
			(roundrect_rratio 0.25)
			(net 115 "VCC")
			(pintype "passive")
		)
		(pad "2" smd roundrect
			(at 0.48 0 270)
			(size 0.59 0.64)
			(layers "F.Cu" "F.Paste" "F.Mask")
			(roundrect_rratio 0.25)
			(net 1 "GND")
			(pintype "passive")
		)
	)
)
